(kicad_pcb
	(version 20260206)
	(generator "pcbnew")
	(generator_version "10.0")
	(general
		(thickness 1.6)
		(legacy_teardrops no)
	)
	(paper "A4")
	(title_block
		(title "peb — Lightning_PEB_BRD.brd")
		(comment 1 "Lightning (Wiwynn / Facebook NVMe JBOF) / footprints 1418-1426 of 2563")
	)
	(layers
		(0 "F.Cu" signal "TOP")
		(4 "In1.Cu" signal "L2GND")
		(6 "In2.Cu" signal "L3")
		(8 "In3.Cu" signal "L4VCC")
		(10 "In4.Cu" signal "L5VCC")
		(12 "In5.Cu" signal "L6")
		(14 "In6.Cu" signal "L7GND")
		(2 "B.Cu" signal "BOTTOM")
		(9 "F.Adhes" user "F.Adhesive")
		(11 "B.Adhes" user "B.Adhesive")
		(13 "F.Paste" user "Package Geometry/Pastemask Top")
		(15 "B.Paste" user "Package Geometry/Pastemask Bottom")
		(5 "F.SilkS" user "Ref Des/Silkscreen Top")
		(7 "B.SilkS" user "Ref Des/Silkscreen Bottom")
		(1 "F.Mask" user "Board Geometry/Soldermask Top")
		(3 "B.Mask" user "Board Geometry/Soldermask Bottom")
		(17 "Dwgs.User" user "User.Drawings")
		(19 "Cmts.User" user "User.Comments")
		(21 "Eco1.User" user "User.Eco1")
		(23 "Eco2.User" user "User.Eco2")
		(25 "Edge.Cuts" user "Board Geometry/Outline")
		(27 "Margin" user)
		(31 "F.CrtYd" user "Package Geometry/Place Bound Top")
		(29 "B.CrtYd" user "Package Geometry/Place Bound Bottom")
		(35 "F.Fab" user "Ref Des/Assembly Top")
		(33 "B.Fab" user "Ref Des/Assembly Bottom")
	)
	(footprint ""
		(layer "F.Cu")
		(at 26.888948 -109.32668 -90)
		(property "Reference" "C286"
			(at 0 0 270)
			(layer "F.SilkS")
			(hide yes)
			(effects
				(font
					(size 1.27 1.27)
				)
			)
		)
		(property "Value" "SCD01U16V2KX-3GP"
			(at 1.1811 -2.7051 270)
			(unlocked yes)
			(layer "F.Fab")
			(hide yes)
			(effects
				(font
					(size 1.016 1.016)
					(thickness 0.1524)
				)
			)
		)
		(property "Device Type" "C402H22"
			(at 1.1811 -4.2291 270)
			(unlocked yes)
			(layer "F.Fab")
			(hide yes)
			(effects
				(font
					(size 1.016 1.016)
					(thickness 0.1524)
				)
			)
		)
		(duplicate_pad_numbers_are_jumpers no)
		(fp_rect
			(start -0.4318 0.9525)
			(end 0.4318 -0.9525)
			(stroke
				(width 0)
				(type default)
			)
			(fill no)
			(layer "F.CrtYd")
		)
		(fp_rect
			(start -0.4318 0.9525)
			(end 0.4318 -0.9525)
			(stroke
				(width 0)
				(type default)
			)
			(fill no)
			(layer "F.Fab")
		)
		(pad "1" smd custom
			(at 0 -0.4445 270)
			(size 0.1524 0.1524)
			(layers "F.Cu" "F.Mask" "F.Paste")
			(net "PCIE_REFCLK_S5_P")
			(options
				(clearance outline)
				(anchor circle)
			)
			(primitives
				(gr_poly
					(pts
						(arc
							(start 0.3048 -0.2032)
							(mid 0.275042 -0.275042)
							(end 0.2032 -0.3048)
						)
						(arc
							(start -0.2032 -0.3048)
							(mid -0.275042 -0.275042)
							(end -0.3048 -0.2032)
						)
						(arc
							(start -0.3048 0.2032)
							(mid -0.275042 0.275042)
							(end -0.2032 0.3048)
						)
						(arc
							(start 0.2032 0.3048)
							(mid 0.275042 0.275042)
							(end 0.3048 0.2032)
						)
					)
					(width 0)
					(fill yes)
				)
			)
		)
		(pad "2" smd custom
			(at 0 0.4445 270)
			(size 0.1524 0.1524)
			(layers "F.Cu" "F.Mask" "F.Paste")
			(net "BMC_REFCLK_P")
			(options
				(clearance outline)
				(anchor circle)
			)
			(primitives
				(gr_poly
					(pts
						(arc
							(start 0.3048 -0.2032)
							(mid 0.275042 -0.275042)
							(end 0.2032 -0.3048)
						)
						(arc
							(start -0.2032 -0.3048)
							(mid -0.275042 -0.275042)
							(end -0.3048 -0.2032)
						)
						(arc
							(start -0.3048 0.2032)
							(mid -0.275042 0.275042)
							(end -0.2032 0.3048)
						)
						(arc
							(start 0.2032 0.3048)
							(mid 0.275042 0.275042)
							(end 0.3048 0.2032)
						)
					)
					(width 0)
					(fill yes)
				)
			)
		)
	)
	(footprint ""
		(layer "F.Cu")
		(at 122.8598 -93.4212 90)
		(property "Reference" "C246"
			(at 0 0 90)
			(layer "F.SilkS")
			(hide yes)
			(effects
				(font
					(size 1.27 1.27)
				)
			)
		)
		(property "Value" "SC220P50V3JN-GP"
			(at 0 -2.8194 90)
			(unlocked yes)
			(layer "F.Fab")
			(hide yes)
			(effects
				(font
					(size 1.016 1.016)
					(thickness 0.1524)
				)
			)
		)
		(property "Device Type" "C603H36"
			(at 0 -4.3434 90)
			(unlocked yes)
			(layer "F.Fab")
			(hide yes)
			(effects
				(font
					(size 1.016 1.016)
					(thickness 0.1524)
				)
			)
		)
		(duplicate_pad_numbers_are_jumpers no)
		(fp_line
			(start 0.508 0)
			(end -0.508 0)
			(stroke
				(width 0.2032)
				(type default)
			)
			(layer "F.SilkS")
		)
		(fp_rect
			(start -0.5842 1.3335)
			(end 0.5842 -1.3335)
			(stroke
				(width 0)
				(type default)
			)
			(fill no)
			(layer "F.CrtYd")
		)
		(fp_rect
			(start -0.5842 1.3335)
			(end 0.5842 -1.3335)
			(stroke
				(width 0)
				(type default)
			)
			(fill no)
			(layer "F.Fab")
		)
		(pad "1" smd custom
			(at 0 -0.762 90)
			(size 0.2159 0.2159)
			(layers "F.Cu" "F.Mask" "F.Paste")
			(net "BMC_I2C10_8536_SCL_R")
			(options
				(clearance outline)
				(anchor circle)
			)
			(primitives
				(gr_poly
					(pts
						(arc
							(start -0.3302 -0.4318)
							(mid -0.402042 -0.402042)
							(end -0.4318 -0.3302)
						)
						(arc
							(start -0.4318 0.3302)
							(mid -0.402042 0.402042)
							(end -0.3302 0.4318)
						)
						(arc
							(start 0.3302 0.4318)
							(mid 0.402042 0.402042)
							(end 0.4318 0.3302)
						)
						(arc
							(start 0.4318 -0.3302)
							(mid 0.402042 -0.402042)
							(end 0.3302 -0.4318)
						)
					)
					(width 0)
					(fill yes)
				)
			)
		)
		(pad "2" smd custom
			(at 0 0.762 90)
			(size 0.2159 0.2159)
			(layers "F.Cu" "F.Mask" "F.Paste")
			(net "GND")
			(options
				(clearance outline)
				(anchor circle)
			)
			(primitives
				(gr_poly
					(pts
						(arc
							(start -0.3302 -0.4318)
							(mid -0.402042 -0.402042)
							(end -0.4318 -0.3302)
						)
						(arc
							(start -0.4318 0.3302)
							(mid -0.402042 0.402042)
							(end -0.3302 0.4318)
						)
						(arc
							(start 0.3302 0.4318)
							(mid 0.402042 0.402042)
							(end 0.4318 0.3302)
						)
						(arc
							(start 0.4318 -0.3302)
							(mid 0.402042 -0.402042)
							(end 0.3302 -0.4318)
						)
					)
					(width 0)
					(fill yes)
				)
			)
		)
	)
	(footprint ""
		(layer "F.Cu")
		(at 62.3062 -153.5176 180)
		(property "Reference" "PG11"
			(at 0 0 180)
			(layer "F.SilkS")
			(hide yes)
			(effects
				(font
					(size 1.27 1.27)
				)
			)
		)
		(property "Value" "GAP-CLOSE-PWR-3-GP"
			(at 0.0254 -6.5786 180)
			(unlocked yes)
			(layer "F.Fab")
			(hide yes)
			(effects
				(font
					(size 1.016 1.016)
					(thickness 0.1524)
				)
			)
		)
		(property "Device Type" "GAP-CLOSE-PWR-3"
			(at 0.0254 -8.255 180)
			(unlocked yes)
			(layer "F.Fab")
			(hide yes)
			(effects
				(font
					(size 1.016 1.016)
					(thickness 0.1524)
				)
			)
		)
		(duplicate_pad_numbers_are_jumpers no)
		(fp_rect
			(start -0.7112 0.4572)
			(end 0.7112 -0.4572)
			(stroke
				(width 0)
				(type default)
			)
			(fill no)
			(layer "F.CrtYd")
		)
		(fp_poly
			(pts
				(xy -0.7112 -0.4572) (xy 0.7112 -0.4572) (xy 0.7112 0.4572) (xy -0.7112 0.4572)
			)
			(stroke
				(width 0)
				(type default)
			)
			(fill no)
			(layer "F.Fab")
		)
		(pad "1" smd rect
			(at -0.3048 0 180)
			(size 0.6604 0.762)
			(layers "F.Cu" "F.Mask" "F.Paste")
			(net "P1V53_PWR")
		)
		(pad "2" smd rect
			(at 0.3048 0 180)
			(size 0.6604 0.762)
			(layers "F.Cu" "F.Mask" "F.Paste")
			(net "P1V53_STBY")
		)
	)
	(footprint ""
		(layer "F.Cu")
		(at 319.670176 -33.507426)
		(property "Reference" "C47"
			(at 0 0 0)
			(layer "F.SilkS")
			(hide yes)
			(effects
				(font
					(size 1.27 1.27)
				)
			)
		)
		(property "Value" "SCD22U10V2KX-1GP"
			(at 1.1811 -2.7051 0)
			(unlocked yes)
			(layer "F.Fab")
			(hide yes)
			(effects
				(font
					(size 1.016 1.016)
					(thickness 0.1524)
				)
			)
		)
		(property "Device Type" "C402H22"
			(at 1.1811 -4.2291 0)
			(unlocked yes)
			(layer "F.Fab")
			(hide yes)
			(effects
				(font
					(size 1.016 1.016)
					(thickness 0.1524)
				)
			)
		)
		(duplicate_pad_numbers_are_jumpers no)
		(fp_rect
			(start -0.4318 0.9525)
			(end 0.4318 -0.9525)
			(stroke
				(width 0)
				(type default)
			)
			(fill no)
			(layer "F.CrtYd")
		)
		(fp_rect
			(start -0.4318 0.9525)
			(end 0.4318 -0.9525)
			(stroke
				(width 0)
				(type default)
			)
			(fill no)
			(layer "F.Fab")
		)
		(pad "1" smd custom
			(at 0 -0.4445)
			(size 0.1524 0.1524)
			(layers "F.Cu" "F.Mask" "F.Paste")
			(net "PCIE_TX_CAP_P12")
			(options
				(clearance outline)
				(anchor circle)
			)
			(primitives
				(gr_poly
					(pts
						(arc
							(start 0.3048 -0.2032)
							(mid 0.275042 -0.275042)
							(end 0.2032 -0.3048)
						)
						(arc
							(start -0.2032 -0.3048)
							(mid -0.275042 -0.275042)
							(end -0.3048 -0.2032)
						)
						(arc
							(start -0.3048 0.2032)
							(mid -0.275042 0.275042)
							(end -0.2032 0.3048)
						)
						(arc
							(start 0.2032 0.3048)
							(mid 0.275042 0.275042)
							(end 0.3048 0.2032)
						)
					)
					(width 0)
					(fill yes)
				)
			)
		)
		(pad "2" smd custom
			(at 0 0.4445)
			(size 0.1524 0.1524)
			(layers "F.Cu" "F.Mask" "F.Paste")
			(net "PCIE_TX_P12")
			(options
				(clearance outline)
				(anchor circle)
			)
			(primitives
				(gr_poly
					(pts
						(arc
							(start 0.3048 -0.2032)
							(mid 0.275042 -0.275042)
							(end 0.2032 -0.3048)
						)
						(arc
							(start -0.2032 -0.3048)
							(mid -0.275042 -0.275042)
							(end -0.3048 -0.2032)
						)
						(arc
							(start -0.3048 0.2032)
							(mid -0.275042 0.275042)
							(end -0.2032 0.3048)
						)
						(arc
							(start 0.2032 0.3048)
							(mid 0.275042 0.275042)
							(end 0.3048 0.2032)
						)
					)
					(width 0)
					(fill yes)
				)
			)
		)
	)
	(footprint ""
		(layer "F.Cu")
		(at 147.0152 -83.7946 -90)
		(property "Reference" "PG70"
			(at 0 0 270)
			(layer "F.SilkS")
			(hide yes)
			(effects
				(font
					(size 1.27 1.27)
				)
			)
		)
		(property "Value" "GAP-CLOSE-PWR-3-GP"
			(at 0.0254 -6.5786 270)
			(unlocked yes)
			(layer "F.Fab")
			(hide yes)
			(effects
				(font
					(size 1.016 1.016)
					(thickness 0.1524)
				)
			)
		)
		(property "Device Type" "GAP-CLOSE-PWR-3"
			(at 0.0254 -8.255 270)
			(unlocked yes)
			(layer "F.Fab")
			(hide yes)
			(effects
				(font
					(size 1.016 1.016)
					(thickness 0.1524)
				)
			)
		)
		(duplicate_pad_numbers_are_jumpers no)
		(fp_rect
			(start -0.7112 0.4572)
			(end 0.7112 -0.4572)
			(stroke
				(width 0)
				(type default)
			)
			(fill no)
			(layer "F.CrtYd")
		)
		(fp_poly
			(pts
				(xy -0.7112 -0.4572) (xy 0.7112 -0.4572) (xy 0.7112 0.4572) (xy -0.7112 0.4572)
			)
			(stroke
				(width 0)
				(type default)
			)
			(fill no)
			(layer "F.Fab")
		)
		(pad "1" smd rect
			(at -0.3048 0 270)
			(size 0.6604 0.762)
			(layers "F.Cu" "F.Mask" "F.Paste")
			(net "P1V8_PWR")
		)
		(pad "2" smd rect
			(at 0.3048 0 270)
			(size 0.6604 0.762)
			(layers "F.Cu" "F.Mask" "F.Paste")
			(net "DUT_VDDO")
		)
	)
	(footprint ""
		(layer "F.Cu")
		(at 13.569188 -90.452956 180)
		(property "Reference" "R476"
			(at 0 0 180)
			(layer "F.SilkS")
			(hide yes)
			(effects
				(font
					(size 1.27 1.27)
				)
			)
		)
		(property "Value" "10KR2F-2-GP"
			(at 0.064008 -3.993896 180)
			(unlocked yes)
			(layer "F.Fab")
			(hide yes)
			(effects
				(font
					(size 1.016 1.016)
					(thickness 0.1524)
				)
			)
		)
		(property "Device Type" "R402H16"
			(at 0.064008 -5.517896 180)
			(unlocked yes)
			(layer "F.Fab")
			(hide yes)
			(effects
				(font
					(size 1.016 1.016)
					(thickness 0.1524)
				)
			)
		)
		(duplicate_pad_numbers_are_jumpers no)
		(fp_line
			(start 0.508 -0.9398)
			(end -0.508 -0.9398)
			(stroke
				(width 0.1524)
				(type default)
			)
			(layer "F.SilkS")
		)
		(fp_line
			(start -0.508 -0.9398)
			(end -0.508 0.9398)
			(stroke
				(width 0.1524)
				(type default)
			)
			(layer "F.SilkS")
		)
		(fp_rect
			(start -0.508 0.9398)
			(end 0.508 -0.9398)
			(stroke
				(width 0)
				(type default)
			)
			(fill no)
			(layer "F.CrtYd")
		)
		(fp_rect
			(start -0.508 0.9398)
			(end 0.508 -0.9398)
			(stroke
				(width 0)
				(type default)
			)
			(fill no)
			(layer "F.Fab")
		)
		(pad "1" smd custom
			(at 0 -0.4445 180)
			(size 0.1397 0.1397)
			(layers "F.Cu" "F.Mask" "F.Paste")
			(net "GND")
			(options
				(clearance outline)
				(anchor circle)
			)
			(primitives
				(gr_poly
					(pts
						(arc
							(start -0.1778 -0.2794)
							(mid -0.249642 -0.249642)
							(end -0.2794 -0.1778)
						)
						(arc
							(start -0.2794 0.1778)
							(mid -0.249642 0.249642)
							(end -0.1778 0.2794)
						)
						(arc
							(start 0.1778 0.2794)
							(mid 0.249642 0.249642)
							(end 0.2794 0.1778)
						)
						(arc
							(start 0.2794 -0.1778)
							(mid 0.249642 -0.249642)
							(end 0.1778 -0.2794)
						)
					)
					(width 0)
					(fill yes)
				)
			)
		)
		(pad "2" smd custom
			(at 0 0.4445 180)
			(size 0.1397 0.1397)
			(layers "F.Cu" "F.Mask" "F.Paste")
			(net "CLK_50M_RMII_PHY")
			(options
				(clearance outline)
				(anchor circle)
			)
			(primitives
				(gr_poly
					(pts
						(arc
							(start -0.1778 -0.2794)
							(mid -0.249642 -0.249642)
							(end -0.2794 -0.1778)
						)
						(arc
							(start -0.2794 0.1778)
							(mid -0.249642 0.249642)
							(end -0.1778 0.2794)
						)
						(arc
							(start 0.1778 0.2794)
							(mid 0.249642 0.249642)
							(end 0.2794 0.1778)
						)
						(arc
							(start 0.2794 -0.1778)
							(mid 0.249642 -0.249642)
							(end 0.1778 -0.2794)
						)
					)
					(width 0)
					(fill yes)
				)
			)
		)
	)
	(footprint ""
		(layer "F.Cu")
		(at 43.6118 -192.8876)
		(property "Reference" "R868"
			(at 0 0 0)
			(layer "F.SilkS")
			(hide yes)
			(effects
				(font
					(size 1.27 1.27)
				)
			)
		)
		(property "Value" "0R2J-2-GP"
			(at 0.064008 -3.993896 0)
			(unlocked yes)
			(layer "F.Fab")
			(hide yes)
			(effects
				(font
					(size 1.016 1.016)
					(thickness 0.1524)
				)
			)
		)
		(property "Device Type" "R402H16"
			(at 0.064008 -5.517896 0)
			(unlocked yes)
			(layer "F.Fab")
			(hide yes)
			(effects
				(font
					(size 1.016 1.016)
					(thickness 0.1524)
				)
			)
		)
		(duplicate_pad_numbers_are_jumpers no)
		(fp_line
			(start -0.508 -0.9398)
			(end -0.508 0.9398)
			(stroke
				(width 0.1524)
				(type default)
			)
			(layer "F.SilkS")
		)
		(fp_line
			(start 0.508 -0.9398)
			(end -0.508 -0.9398)
			(stroke
				(width 0.1524)
				(type default)
			)
			(layer "F.SilkS")
		)
		(fp_rect
			(start -0.508 0.9398)
			(end 0.508 -0.9398)
			(stroke
				(width 0)
				(type default)
			)
			(fill no)
			(layer "F.CrtYd")
		)
		(fp_rect
			(start -0.508 0.9398)
			(end 0.508 -0.9398)
			(stroke
				(width 0)
				(type default)
			)
			(fill no)
			(layer "F.Fab")
		)
		(pad "1" smd custom
			(at 0 -0.4445)
			(size 0.1397 0.1397)
			(layers "F.Cu" "F.Mask" "F.Paste")
			(net "BUF_I2C9_CLKBUF2_SCL")
			(options
				(clearance outline)
				(anchor circle)
			)
			(primitives
				(gr_poly
					(pts
						(arc
							(start -0.1778 -0.2794)
							(mid -0.249642 -0.249642)
							(end -0.2794 -0.1778)
						)
						(arc
							(start -0.2794 0.1778)
							(mid -0.249642 0.249642)
							(end -0.1778 0.2794)
						)
						(arc
							(start 0.1778 0.2794)
							(mid 0.249642 0.249642)
							(end 0.2794 0.1778)
						)
						(arc
							(start 0.2794 -0.1778)
							(mid 0.249642 -0.249642)
							(end 0.1778 -0.2794)
						)
					)
					(width 0)
					(fill yes)
				)
			)
		)
		(pad "2" smd custom
			(at 0 0.4445)
			(size 0.1397 0.1397)
			(layers "F.Cu" "F.Mask" "F.Paste")
			(net "BUF_I2C9_CLKBUF2_SCL_R")
			(options
				(clearance outline)
				(anchor circle)
			)
			(primitives
				(gr_poly
					(pts
						(arc
							(start -0.1778 -0.2794)
							(mid -0.249642 -0.249642)
							(end -0.2794 -0.1778)
						)
						(arc
							(start -0.2794 0.1778)
							(mid -0.249642 0.249642)
							(end -0.1778 0.2794)
						)
						(arc
							(start 0.1778 0.2794)
							(mid 0.249642 0.249642)
							(end 0.2794 0.1778)
						)
						(arc
							(start 0.2794 -0.1778)
							(mid 0.249642 -0.249642)
							(end 0.1778 -0.2794)
						)
					)
					(width 0)
					(fill yes)
				)
			)
		)
	)
	(footprint ""
		(layer "F.Cu")
		(at 265.028172 -8.627364)
		(property "Reference" "C375"
			(at 0 0 0)
			(layer "F.SilkS")
			(hide yes)
			(effects
				(font
					(size 1.27 1.27)
				)
			)
		)
		(property "Value" "SCD1U25V2KX-2-GP"
			(at 1.1811 -2.7051 0)
			(unlocked yes)
			(layer "F.Fab")
			(hide yes)
			(effects
				(font
					(size 1.016 1.016)
					(thickness 0.1524)
				)
			)
		)
		(property "Device Type" "C402H22"
			(at 1.1811 -4.2291 0)
			(unlocked yes)
			(layer "F.Fab")
			(hide yes)
			(effects
				(font
					(size 1.016 1.016)
					(thickness 0.1524)
				)
			)
		)
		(duplicate_pad_numbers_are_jumpers no)
		(fp_rect
			(start -0.4318 0.9525)
			(end 0.4318 -0.9525)
			(stroke
				(width 0)
				(type default)
			)
			(fill no)
			(layer "F.CrtYd")
		)
		(fp_rect
			(start -0.4318 0.9525)
			(end 0.4318 -0.9525)
			(stroke
				(width 0)
				(type default)
			)
			(fill no)
			(layer "F.Fab")
		)
		(pad "1" smd custom
			(at 0 -0.4445)
			(size 0.1524 0.1524)
			(layers "F.Cu" "F.Mask" "F.Paste")
			(net "P3V3_STBY")
			(options
				(clearance outline)
				(anchor circle)
			)
			(primitives
				(gr_poly
					(pts
						(arc
							(start 0.3048 -0.2032)
							(mid 0.275042 -0.275042)
							(end 0.2032 -0.3048)
						)
						(arc
							(start -0.2032 -0.3048)
							(mid -0.275042 -0.275042)
							(end -0.3048 -0.2032)
						)
						(arc
							(start -0.3048 0.2032)
							(mid -0.275042 0.275042)
							(end -0.2032 0.3048)
						)
						(arc
							(start 0.2032 0.3048)
							(mid 0.275042 0.275042)
							(end 0.3048 0.2032)
						)
					)
					(width 0)
					(fill yes)
				)
			)
		)
		(pad "2" smd custom
			(at 0 0.4445)
			(size 0.1524 0.1524)
			(layers "F.Cu" "F.Mask" "F.Paste")
			(net "GND")
			(options
				(clearance outline)
				(anchor circle)
			)
			(primitives
				(gr_poly
					(pts
						(arc
							(start 0.3048 -0.2032)
							(mid 0.275042 -0.275042)
							(end 0.2032 -0.3048)
						)
						(arc
							(start -0.2032 -0.3048)
							(mid -0.275042 -0.275042)
							(end -0.3048 -0.2032)
						)
						(arc
							(start -0.3048 0.2032)
							(mid -0.275042 0.275042)
							(end -0.2032 0.3048)
						)
						(arc
							(start 0.2032 0.3048)
							(mid 0.275042 0.275042)
							(end 0.3048 0.2032)
						)
					)
					(width 0)
					(fill yes)
				)
			)
		)
	)
	(footprint ""
		(layer "F.Cu")
		(at 180.9242 -71.628 180)
		(property "Reference" "C554"
			(at 0 0 180)
			(layer "F.SilkS")
			(hide yes)
			(effects
				(font
					(size 1.27 1.27)
				)
			)
		)
		(property "Value" "SC4D7U16V5KX-1-GP"
			(at -0.0762 -6.1214 180)
			(unlocked yes)
			(layer "F.Fab")
			(hide yes)
			(effects
				(font
					(size 1.016 1.016)
					(thickness 0.1524)
				)
			)
		)
		(property "Device Type" "C805H56"
			(at -0.0762 -8.1534 180)
			(unlocked yes)
			(layer "F.Fab")
			(hide yes)
			(effects
				(font
					(size 1.016 1.016)
					(thickness 0.1524)
				)
			)
		)
		(duplicate_pad_numbers_are_jumpers no)
		(fp_line
			(start 0.635 0)
			(end -0.635 0)
			(stroke
				(width 0.508)
				(type default)
			)
			(layer "F.SilkS")
		)
		(fp_rect
			(start -0.9652 1.778)
			(end 0.9652 -1.778)
			(stroke
				(width 0)
				(type default)
			)
			(fill no)
			(layer "F.CrtYd")
		)
		(fp_poly
			(pts
				(xy -0.9652 -1.778) (xy 0.9652 -1.778) (xy 0.9652 1.778) (xy -0.9652 1.778)
			)
			(stroke
				(width 0)
				(type default)
			)
			(fill no)
			(layer "F.Fab")
		)
		(pad "1" smd rect
			(at 0 -0.9652 180)
			(size 1.397 1.143)
			(layers "F.Cu" "F.Mask" "F.Paste")
			(net "DUT_AVD_PCIE")
		)
		(pad "2" smd rect
			(at 0 0.9652 180)
			(size 1.397 1.143)
			(layers "F.Cu" "F.Mask" "F.Paste")
			(net "GND")
		)
	)
)
